# BASEBOARD_FAB2 (Tioga Pass) — schematic netlist excerpt (pin names and nets, part order shuffled) for the footprints in the layout excerpt that follows; sources: Cadence DE-HDL packaged netlist, KiCad conversion of Wiwynn_Tioga_Pass_MB.brd

C2N13  CAP_A  1.0UF 6.3V 10% X6S  pkg 0402V  page 131 : A = P1V05_PCH_STBY ; B = GND
R25W184  RES  0.0 5% CHIP  pkg 0402  page 146 : A = RST_BMC_PLTRST_BUF_N ; B = RST_PLTRST_BUF_N

Q25W4  FET_N_DUAL  2N7002DW FET  pkg SMLF  page 252
  SOURCE(0)  = I2C_BMC_VGA_DDC_SCL
  GATE(0)  = Q25W1_GATE
  DRAIN(0)  = I2C_BMC_VGA_DDC_SDA_G
  SOURCE(0)  = I2C_BMC_VGA_DDC_SDA
  GATE(0)  = Q25W2_GATE
  DRAIN(0)  = I2C_BMC_VGA_DDC_SCL_G

(kicad_pcb
	(version 20260206)
	(generator "pcbnew")
	(generator_version "10.0")
	(general
		(thickness 1.6)
		(legacy_teardrops no)
	)
	(paper "A4")
	(title_block
		(title "Wiwynn_Tioga_Pass_MB.brd")
		(comment 1 "Tioga Pass / footprints 3652-3654 of 4770")
	)
	(layers
		(0 "F.Cu" signal "TOP")
		(4 "In1.Cu" signal "L2GND")
		(6 "In2.Cu" signal "L3")
		(8 "In3.Cu" signal "L4GND")
		(10 "In4.Cu" signal "L5")
		(12 "In5.Cu" signal "L6GND")
		(14 "In6.Cu" signal "L7VCC")
		(16 "In7.Cu" signal "L8VCC")
		(18 "In8.Cu" signal "L9GND")
		(20 "In9.Cu" signal "L10")
		(22 "In10.Cu" signal "L11GND")
		(24 "In11.Cu" signal "L12")
		(26 "In12.Cu" signal "L13GND")
		(2 "B.Cu" signal "BOTTOM")
		(9 "F.Adhes" user "F.Adhesive")
		(11 "B.Adhes" user "B.Adhesive")
		(13 "F.Paste" user "Package Geometry/Pastemask Top")
		(15 "B.Paste" user "Package Geometry/Pastemask Bottom")
		(5 "F.SilkS" user "Ref Des/Silkscreen Top")
		(7 "B.SilkS" user "Ref Des/Silkscreen Bottom")
		(1 "F.Mask" user "Board Geometry/Soldermask Top")
		(3 "B.Mask" user "Board Geometry/Soldermask Bottom")
		(17 "Dwgs.User" user "User.Drawings")
		(19 "Cmts.User" user "User.Comments")
		(21 "Eco1.User" user "User.Eco1")
		(23 "Eco2.User" user "User.Eco2")
		(25 "Edge.Cuts" user "Board Geometry/Outline")
		(27 "Margin" user)
		(31 "F.CrtYd" user "Package Geometry/Place Bound Top")
		(29 "B.CrtYd" user "Package Geometry/Place Bound Bottom")
		(35 "F.Fab" user "Ref Des/Assembly Top")
		(33 "B.Fab" user "Ref Des/Assembly Bottom")
	)
	(footprint ""
		(layer "B.Cu")
		(at 393.65047 -106.58221)
		(property "Reference" "C2N13"
			(at 0 0 0)
			(layer "B.SilkS")
			(hide yes)
			(effects
				(font
					(size 1.27 1.27)
				)
				(justify mirror)
			)
		)
		(property "Value" ""
			(at 0 0 0)
			(layer "B.Fab")
			(effects
				(font
					(size 1.27 1.27)
				)
				(justify mirror)
			)
		)
		(duplicate_pad_numbers_are_jumpers no)
		(fp_rect
			(start 0.2794 0.9144)
			(end -0.2794 -0.1143)
			(stroke
				(width 0)
				(type default)
			)
			(fill no)
			(layer "B.CrtYd")
		)
		(fp_line
			(start -0.2794 -0.1143)
			(end -0.2794 0.9144)
			(stroke
				(width 0.1)
				(type default)
			)
			(layer "B.Fab")
		)
		(fp_line
			(start -0.2794 0.9144)
			(end 0.2794 0.9144)
			(stroke
				(width 0.1)
				(type default)
			)
			(layer "B.Fab")
		)
		(fp_line
			(start 0.2794 -0.1143)
			(end -0.2794 -0.1143)
			(stroke
				(width 0.1)
				(type default)
			)
			(layer "B.Fab")
		)
		(fp_line
			(start 0.2794 0.9144)
			(end 0.2794 -0.1143)
			(stroke
				(width 0.1)
				(type default)
			)
			(layer "B.Fab")
		)
		(pad "1" smd custom
			(at 0 0 270)
			(size 0.10414 0.10414)
			(layers "B.Cu" "B.Mask" "B.Paste")
			(net "P1V05_PCH_STBY")
			(options
				(clearance outline)
				(anchor circle)
			)
			(primitives
				(gr_poly
					(pts
						(xy -0.20828 -0.08636) (xy -0.20828 0.08636) (xy -0.08636 0.20828) (xy 0.086614 0.20828) (xy 0.20828 0.086614)
						(xy 0.20828 -0.08636) (xy 0.08636 -0.20828) (xy -0.08636 -0.20828)
					)
					(width 0)
					(fill yes)
				)
			)
		)
		(pad "2" smd custom
			(at 0 0.8001 270)
			(size 0.10414 0.10414)
			(layers "B.Cu" "B.Mask" "B.Paste")
			(net "GND")
			(options
				(clearance outline)
				(anchor circle)
			)
			(primitives
				(gr_poly
					(pts
						(xy -0.20828 -0.08636) (xy -0.20828 0.08636) (xy -0.08636 0.20828) (xy 0.086614 0.20828) (xy 0.20828 0.086614)
						(xy 0.20828 -0.08636) (xy 0.08636 -0.20828) (xy -0.08636 -0.20828)
					)
					(width 0)
					(fill yes)
				)
			)
		)
		(zone
			(layer "B.Cu")
			(hatch none 0.5)
			(connect_pads
				(clearance 0)
			)
			(min_thickness 0.25)
			(keepout
				(tracks not_allowed)
				(vias allowed)
				(pads allowed)
				(copperpour not_allowed)
				(footprints allowed)
			)
			(placement
				(enabled no)
				(sheetname "")
			)
			(fill
				(thermal_gap 0.5)
				(thermal_bridge_width 0.5)
				(island_removal_mode 0)
			)
			(polygon
				(pts
					(xy 393.7381 -106.37266) (xy 393.7381 -105.99166) (xy 393.56284 -105.99166) (xy 393.562586 -106.37266)
				)
			)
		)
		(zone
			(layer "B.Cu")
			(hatch none 0.5)
			(connect_pads
				(clearance 0)
			)
			(min_thickness 0.25)
			(keepout
				(tracks allowed)
				(vias not_allowed)
				(pads allowed)
				(copperpour not_allowed)
				(footprints allowed)
			)
			(placement
				(enabled no)
				(sheetname "")
			)
			(fill
				(thermal_gap 0.5)
				(thermal_bridge_width 0.5)
				(island_removal_mode 0)
			)
			(polygon
				(pts
					(xy 393.7381 -106.37266) (xy 393.7381 -105.99166) (xy 393.56284 -105.99166) (xy 393.562586 -106.37266)
				)
			)
		)
	)
	(footprint ""
		(layer "B.Cu")
		(at 493.137698 -46.533816 -90)
		(property "Reference" "Q25W4"
			(at 0 -0.81788 270)
			(unlocked yes)
			(layer "B.SilkS")
			(effects
				(font
					(size 0.4064 0.254)
					(thickness 0.1524)
				)
				(justify left mirror)
			)
		)
		(property "Value" ""
			(at 0 0 90)
			(layer "B.Fab")
			(effects
				(font
					(size 1.27 1.27)
				)
				(justify mirror)
			)
		)
		(duplicate_pad_numbers_are_jumpers no)
		(fp_circle
			(center 0.848614 -0.6477)
			(end 0.848614 -0.7747)
			(stroke
				(width 0.254)
				(type default)
			)
			(fill no)
			(layer "B.SilkS")
		)
		(fp_poly
			(pts
				(xy -0.21463 -0.450088) (xy -1.56337 -0.450088) (xy -1.56337 1.75006) (xy -0.21463 1.75006)
			)
			(stroke
				(width 0)
				(type default)
			)
			(fill no)
			(layer "B.CrtYd")
		)
		(fp_line
			(start -1.56337 1.75006)
			(end -0.21463 1.75006)
			(stroke
				(width 0.1)
				(type default)
			)
			(layer "B.Fab")
		)
		(fp_line
			(start -0.21463 1.75006)
			(end -0.21463 -0.450088)
			(stroke
				(width 0.1)
				(type default)
			)
			(layer "B.Fab")
		)
		(fp_line
			(start -1.56337 -0.450088)
			(end -1.56337 1.75006)
			(stroke
				(width 0.1)
				(type default)
			)
			(layer "B.Fab")
		)
		(fp_line
			(start -0.21463 -0.450088)
			(end -1.56337 -0.450088)
			(stroke
				(width 0.1)
				(type default)
			)
			(layer "B.Fab")
		)
		(fp_circle
			(center 0.848614 -0.6477)
			(end 0.848614 -0.7747)
			(stroke
				(width 0.254)
				(type default)
			)
			(fill no)
			(layer "B.Fab")
		)
		(pad "1" smd rect
			(at 0 0 90)
			(size 1.016 0.381)
			(layers "B.Cu" "B.Mask" "B.Paste")
			(net "I2C_BMC_VGA_DDC_SCL")
		)
		(pad "2" smd rect
			(at 0 0.649986 90)
			(size 1.016 0.381)
			(layers "B.Cu" "B.Mask" "B.Paste")
			(net "Q25W1_GATE")
		)
		(pad "3" smd rect
			(at 0 1.299972 90)
			(size 1.016 0.381)
			(layers "B.Cu" "B.Mask" "B.Paste")
			(net "I2C_BMC_VGA_DDC_SDA_G")
		)
		(pad "4" smd rect
			(at -1.778 1.299972 90)
			(size 1.016 0.381)
			(layers "B.Cu" "B.Mask" "B.Paste")
			(net "I2C_BMC_VGA_DDC_SDA")
		)
		(pad "5" smd rect
			(at -1.778 0.649986 90)
			(size 1.016 0.381)
			(layers "B.Cu" "B.Mask" "B.Paste")
			(net "Q25W2_GATE")
		)
		(pad "6" smd rect
			(at -1.778 0 90)
			(size 1.016 0.381)
			(layers "B.Cu" "B.Mask" "B.Paste")
			(net "I2C_BMC_VGA_DDC_SCL_G")
		)
	)
	(footprint ""
		(layer "B.Cu")
		(at 423.342054 -44.706794 180)
		(property "Reference" "R25W184"
			(at 0.8382 -0.67818 180)
			(unlocked yes)
			(layer "B.SilkS")
			(effects
				(font
					(size 0.4064 0.254)
					(thickness 0.1524)
				)
				(justify left mirror)
			)
		)
		(property "Value" ""
			(at 0 0 0)
			(layer "B.Fab")
			(effects
				(font
					(size 1.27 1.27)
				)
				(justify mirror)
			)
		)
		(duplicate_pad_numbers_are_jumpers no)
		(fp_poly
			(pts
				(xy 0.2794 -0.1016) (xy -0.2794 -0.1016) (xy -0.2794 0.9906) (xy 0.2794 0.9906)
			)
			(stroke
				(width 0)
				(type default)
			)
			(fill no)
			(layer "B.CrtYd")
		)
		(fp_line
			(start 0.2794 0.9906)
			(end -0.2794 0.9906)
			(stroke
				(width 0.1)
				(type default)
			)
			(layer "B.Fab")
		)
		(fp_line
			(start 0.2794 -0.1016)
			(end 0.2794 0.9906)
			(stroke
				(width 0.1)
				(type default)
			)
			(layer "B.Fab")
		)
		(fp_line
			(start -0.2794 0.9906)
			(end -0.2794 -0.1016)
			(stroke
				(width 0.1)
				(type default)
			)
			(layer "B.Fab")
		)
		(fp_line
			(start -0.2794 -0.1016)
			(end 0.2794 -0.1016)
			(stroke
				(width 0.1)
				(type default)
			)
			(layer "B.Fab")
		)
		(pad "1" smd rect
			(at 0 0)
			(size 0.508 0.508)
			(layers "B.Cu" "B.Mask" "B.Paste")
			(net "RST_BMC_PLTRST_BUF_N")
		)
		(pad "2" smd rect
			(at 0 0.889)
			(size 0.508 0.508)
			(layers "B.Cu" "B.Mask" "B.Paste")
			(net "RST_PLTRST_BUF_N")
		)
		(zone
			(layer "B.Cu")
			(hatch none 0.5)
			(connect_pads
				(clearance 0)
			)
			(min_thickness 0.25)
			(keepout
				(tracks not_allowed)
				(vias allowed)
				(pads allowed)
				(copperpour not_allowed)
				(footprints allowed)
			)
			(placement
				(enabled no)
				(sheetname "")
			)
			(fill
				(thermal_gap 0.5)
				(thermal_bridge_width 0.5)
				(island_removal_mode 0)
			)
			(polygon
				(pts
					(xy 423.088054 -45.341794) (xy 423.596054 -45.341794) (xy 423.596054 -44.960794) (xy 423.088054 -44.960794)
				)
			)
		)
		(zone
			(layer "B.Cu")
			(hatch none 0.5)
			(connect_pads
				(clearance 0)
			)
			(min_thickness 0.25)
			(keepout
				(tracks allowed)
				(vias not_allowed)
				(pads allowed)
				(copperpour not_allowed)
				(footprints allowed)
			)
			(placement
				(enabled no)
				(sheetname "")
			)
			(fill
				(thermal_gap 0.5)
				(thermal_bridge_width 0.5)
				(island_removal_mode 0)
			)
			(polygon
				(pts
					(xy 423.088054 -44.960794) (xy 423.596054 -44.960794) (xy 423.596054 -45.341794) (xy 423.088054 -45.341794)
				)
			)
		)
	)
)
